(kicad_pcb
	(version 20241229)
	(generator "pcbnew")
	(generator_version "9.0")
	(general
		(thickness 1.59)
		(legacy_teardrops no)
	)
	(paper "A3")
	(title_block
		(title "usb-c-power-adapter")
		(date "2025-06-24")
		(rev "1.1.2")
		(company "Antmicro")
		(comment 9 "footprints 38-40 of 122")
	)
	(layers
		(0 "F.Cu" signal)
		(4 "In1.Cu" signal)
		(6 "In2.Cu" signal)
		(2 "B.Cu" signal)
		(9 "F.Adhes" user "F.Adhesive")
		(11 "B.Adhes" user "B.Adhesive")
		(13 "F.Paste" user)
		(15 "B.Paste" user)
		(5 "F.SilkS" user "F.Silkscreen")
		(7 "B.SilkS" user "B.Silkscreen")
		(1 "F.Mask" user)
		(3 "B.Mask" user)
		(17 "Dwgs.User" user "User.Drawings")
		(19 "Cmts.User" user "User.Comments")
		(21 "Eco1.User" user "User.Eco1")
		(23 "Eco2.User" user "User.Eco2")
		(25 "Edge.Cuts" user)
		(27 "Margin" user)
		(31 "F.CrtYd" user "F.Courtyard")
		(29 "B.CrtYd" user "B.Courtyard")
		(35 "F.Fab" user)
		(33 "B.Fab" user)
	)
	(footprint "antmicro-footprints:R_0402_1005Metric"
		(layer "F.Cu")
		(at 100 83.577 180)
		(descr "Resistor SMD 0402")
		(tags "resistor SMD 0402")
		(property "Reference" "R18"
			(at -1.092 -0.497 0)
			(layer "F.SilkS")
			(effects
				(font
					(size 0.7 0.7)
					(thickness 0.15)
				)
				(justify left bottom)
			)
		)
		(property "Value" "R_10k_0.1%_0402"
			(at -1.011843 1.772047 0)
			(layer "F.Fab")
			(effects
				(font
					(size 0.7 0.7)
					(thickness 0.15)
				)
				(justify right bottom)
			)
		)
		(property "Datasheet" "https://www.mouser.com/datasheet/2/54/CRT-1649066.pdf"
			(at 0 0 180)
			(layer "F.Fab")
			(hide yes)
			(effects
				(font
					(size 1.27 1.27)
					(thickness 0.15)
				)
			)
		)
		(property "Description" "SMD Chip Resistor, 10 kohm, ± 0.1%, 62.5 mW, 0402 [1005 Metric], Thin Film, Precision Resistors"
			(at 0 0 180)
			(layer "F.Fab")
			(hide yes)
			(effects
				(font
					(size 1.27 1.27)
					(thickness 0.15)
				)
			)
		)
		(property "MPN" "CRT0402-BY-1002GLF "
			(at 0 0 180)
			(unlocked yes)
			(layer "F.Fab")
			(hide yes)
			(effects
				(font
					(size 1 1)
					(thickness 0.15)
				)
			)
		)
		(property "Val" "10k"
			(at 0 0 180)
			(unlocked yes)
			(layer "F.Fab")
			(hide yes)
			(effects
				(font
					(size 1 1)
					(thickness 0.15)
				)
			)
		)
		(property "Manufacturer" "Bourns"
			(at 0 0 180)
			(unlocked yes)
			(layer "F.Fab")
			(hide yes)
			(effects
				(font
					(size 1 1)
					(thickness 0.15)
				)
			)
		)
		(property "Tolerance" "0.1%"
			(at 0 0 180)
			(unlocked yes)
			(layer "F.Fab")
			(hide yes)
			(effects
				(font
					(size 1 1)
					(thickness 0.15)
				)
			)
		)
		(property "License" "Apache-2.0"
			(at 0 0 180)
			(unlocked yes)
			(layer "F.Fab")
			(hide yes)
			(effects
				(font
					(size 1 1)
					(thickness 0.15)
				)
			)
		)
		(property "Author" "Antmicro"
			(at 0 0 180)
			(unlocked yes)
			(layer "F.Fab")
			(hide yes)
			(effects
				(font
					(size 1 1)
					(thickness 0.15)
				)
			)
		)
		(sheetname "/DC-DC Converters/")
		(sheetfile "dc-dc_converters.kicad_sch")
		(attr smd)
		(fp_rect
			(start -0.925 -0.47)
			(end 0.925 0.47)
			(stroke
				(width 0.05)
				(type default)
			)
			(fill no)
			(layer "F.CrtYd")
		)
		(fp_rect
			(start -0.5 -0.25)
			(end 0.5 0.25)
			(stroke
				(width 0.15)
				(type solid)
			)
			(fill no)
			(layer "F.Fab")
		)
		(pad "1" smd roundrect
			(at -0.48 0 180)
			(size 0.59 0.64)
			(layers "F.Cu" "F.Mask" "F.Paste")
			(roundrect_rratio 0.25)
			(net 2 "GND")
			(pintype "passive")
		)
		(pad "2" smd roundrect
			(at 0.48 0 180)
			(size 0.59 0.64)
			(layers "F.Cu" "F.Mask" "F.Paste")
			(roundrect_rratio 0.25)
			(net 51 "Net-(U2-V_{FB})")
			(pintype "passive")
		)
	)
	(footprint "antmicro-footprints:R_0402_1005Metric"
		(layer "F.Cu")
		(at 101.226 72.35 90)
		(descr "Resistor SMD 0402")
		(tags "resistor SMD 0402")
		(property "Reference" "R29"
			(at -6.898 -2.752 0)
			(layer "B.SilkS")
			(effects
				(font
					(size 0.7 0.7)
					(thickness 0.15)
				)
				(justify left bottom mirror)
			)
		)
		(property "Value" "R_470_0402"
			(at -1.011843 1.772047 90)
			(layer "F.Fab")
			(effects
				(font
					(size 0.7 0.7)
					(thickness 0.15)
				)
				(justify left bottom)
			)
		)
		(property "Datasheet" "https://www.bourns.com/docs/product-datasheets/cr.pdf"
			(at 0 0 90)
			(layer "F.Fab")
			(hide yes)
			(effects
				(font
					(size 1.27 1.27)
					(thickness 0.15)
				)
			)
		)
		(property "Description" "SMD Chip Resistor, 470 ohm, ± 1%, 62.5 mW, 0402 [1005 Metric], Thick Film, General Purpose"
			(at 0 0 90)
			(layer "F.Fab")
			(hide yes)
			(effects
				(font
					(size 1.27 1.27)
					(thickness 0.15)
				)
			)
		)
		(property "MPN" "CR0402-FX-4700GLF"
			(at 0 0 90)
			(unlocked yes)
			(layer "F.Fab")
			(hide yes)
			(effects
				(font
					(size 1 1)
					(thickness 0.15)
				)
			)
		)
		(property "Manufacturer" "Bourns"
			(at 0 0 90)
			(unlocked yes)
			(layer "F.Fab")
			(hide yes)
			(effects
				(font
					(size 1 1)
					(thickness 0.15)
				)
			)
		)
		(property "License" "Apache-2.0"
			(at 0 0 90)
			(unlocked yes)
			(layer "F.Fab")
			(hide yes)
			(effects
				(font
					(size 1 1)
					(thickness 0.15)
				)
			)
		)
		(property "Author" "Antmicro"
			(at 0 0 90)
			(unlocked yes)
			(layer "F.Fab")
			(hide yes)
			(effects
				(font
					(size 1 1)
					(thickness 0.15)
				)
			)
		)
		(property "Val" "470R"
			(at 0 0 90)
			(unlocked yes)
			(layer "F.Fab")
			(hide yes)
			(effects
				(font
					(size 1 1)
					(thickness 0.15)
				)
			)
		)
		(property "Tolerance" "1%"
			(at 0 0 90)
			(unlocked yes)
			(layer "F.Fab")
			(hide yes)
			(effects
				(font
					(size 1 1)
					(thickness 0.15)
				)
			)
		)
		(sheetname "/DC-DC Converters/")
		(sheetfile "dc-dc_converters.kicad_sch")
		(attr smd)
		(fp_rect
			(start -0.925 -0.47)
			(end 0.925 0.47)
			(stroke
				(width 0.05)
				(type default)
			)
			(fill no)
			(layer "F.CrtYd")
		)
		(fp_rect
			(start -0.5 -0.25)
			(end 0.5 0.25)
			(stroke
				(width 0.15)
				(type solid)
			)
			(fill no)
			(layer "F.Fab")
		)
		(pad "1" smd roundrect
			(at -0.48 0 90)
			(size 0.59 0.64)
			(layers "F.Cu" "F.Mask" "F.Paste")
			(roundrect_rratio 0.25)
			(net 68 "Net-(D8-A)")
			(pintype "passive")
		)
		(pad "2" smd roundrect
			(at 0.48 0 90)
			(size 0.59 0.64)
			(layers "F.Cu" "F.Mask" "F.Paste")
			(roundrect_rratio 0.25)
			(net 25 "+5V")
			(pintype "passive")
		)
	)
	(footprint "antmicro-footprints:LED_0603_1608Metric_G"
		(layer "F.Cu")
		(at 97 74.55 90)
		(descr "LED SMD 0603 Green")
		(tags "LED SMD 0603 Green")
		(property "Reference" "D3"
			(at -7.8 1.476 0)
			(layer "B.SilkS")
			(effects
				(font
					(size 0.7 0.7)
					(thickness 0.15)
				)
				(justify right bottom mirror)
			)
		)
		(property "Value" "LED_G_0603_LG_L29K-G2J1-24-Z"
			(at -0.001 1.599 90)
			(layer "F.Fab")
			(effects
				(font
					(size 0.7 0.7)
					(thickness 0.15)
				)
				(justify left bottom)
			)
		)
		(property "Datasheet" "https://look.ams-osram.com/m/19ee86b3ae0ee95b/original/LG-L29K.pdf"
			(at 0 0 90)
			(layer "F.Fab")
			(hide yes)
			(effects
				(font
					(size 1.27 1.27)
					(thickness 0.15)
				)
			)
		)
		(property "Description" "LED, Green, SMD, 0603, 20 mA, 1.7 V, 570 nm"
			(at 0 0 90)
			(layer "F.Fab")
			(hide yes)
			(effects
				(font
					(size 1.27 1.27)
					(thickness 0.15)
				)
			)
		)
		(property "MPN" "LG L29K-G2J1-24-Z"
			(at 0 0 90)
			(unlocked yes)
			(layer "F.Fab")
			(hide yes)
			(effects
				(font
					(size 1 1)
					(thickness 0.15)
				)
			)
		)
		(property "Manufacturer" "OSRAM"
			(at 0 0 90)
			(unlocked yes)
			(layer "F.Fab")
			(hide yes)
			(effects
				(font
					(size 1 1)
					(thickness 0.15)
				)
			)
		)
		(property "Color" "Green"
			(at 0 0 90)
			(unlocked yes)
			(layer "F.Fab")
			(hide yes)
			(effects
				(font
					(size 1 1)
					(thickness 0.15)
				)
			)
		)
		(property "Author" "Antmicro"
			(at 0 0 90)
			(unlocked yes)
			(layer "F.Fab")
			(hide yes)
			(effects
				(font
					(size 1 1)
					(thickness 0.15)
				)
			)
		)
		(property "License" "Apache-2.0"
			(at 0 0 90)
			(unlocked yes)
			(layer "F.Fab")
			(hide yes)
			(effects
				(font
					(size 1 1)
					(thickness 0.15)
				)
			)
		)
		(sheetname "/USB PD/")
		(sheetfile "usb_pd.kicad_sch")
		(attr smd)
		(fp_line
			(start 0.22 -0.35)
			(end -0.22 -0.35)
			(stroke
				(width 0.15)
				(type solid)
			)
			(layer "F.SilkS")
		)
		(fp_line
			(start -1.18 -0.319)
			(end -1.18 0.321)
			(stroke
				(width 0.15)
				(type solid)
			)
			(layer "F.SilkS")
		)
		(fp_line
			(start 0.105328 0.001008)
			(end 0.24 0.001)
			(stroke
				(width 0.1)
				(type solid)
			)
			(layer "F.SilkS")
		)
		(fp_line
			(start -0.094672 0.001008)
			(end 0.105328 -0.198992)
			(stroke
				(width 0.1)
				(type solid)
			)
			(layer "F.SilkS")
		)
		(fp_line
			(start -0.094672 0.001008)
			(end -0.24 0.001008)
			(stroke
				(width 0.1)
				(type solid)
			)
			(layer "F.SilkS")
		)
		(fp_line
			(start 0.105328 0.201008)
			(end 0.105328 -0.198992)
			(stroke
				(width 0.1)
				(type solid)
			)
			(layer "F.SilkS")
		)
		(fp_line
			(start 0.105328 0.201008)
			(end -0.094672 0.001008)
			(stroke
				(width 0.1)
				(type solid)
			)
			(layer "F.SilkS")
		)
		(fp_line
			(start -0.094672 0.201008)
			(end -0.094672 -0.198992)
			(stroke
				(width 0.1)
				(type solid)
			)
			(layer "F.SilkS")
		)
		(fp_line
			(start 0.22 0.35)
			(end -0.22 0.35)
			(stroke
				(width 0.15)
				(type solid)
			)
			(layer "F.SilkS")
		)
		(fp_rect
			(start 1.25 0.65)
			(end -1.25 -0.65)
			(stroke
				(width 0.05)
				(type solid)
			)
			(fill no)
			(layer "F.CrtYd")
		)
		(fp_line
			(start 0.201 -0.202)
			(end -0.101 0)
			(stroke
				(width 0.15)
				(type solid)
			)
			(layer "F.Fab")
		)
		(fp_line
			(start -0.199 -0.202)
			(end -0.199 0.1)
			(stroke
				(width 0.15)
				(type solid)
			)
			(layer "F.Fab")
		)
		(fp_line
			(start 0.599 0)
			(end 0.201 0)
			(stroke
				(width 0.15)
				(type solid)
			)
			(layer "F.Fab")
		)
		(fp_line
			(start 0.201 0)
			(end 0.201 -0.202)
			(stroke
				(width 0.15)
				(type solid)
			)
			(layer "F.Fab")
		)
		(fp_line
			(start -0.101 0)
			(end 0.201 0.2)
			(stroke
				(width 0.15)
				(type solid)
			)
			(layer "F.Fab")
		)
		(fp_line
			(start -0.199 0)
			(end -0.597 0)
			(stroke
				(width 0.15)
				(type solid)
			)
			(layer "F.Fab")
		)
		(fp_line
			(start 0.201 0.2)
			(end 0.201 0)
			(stroke
				(width 0.15)
				(type solid)
			)
			(layer "F.Fab")
		)
		(fp_line
			(start -0.199 0.2)
			(end -0.199 0.1)
			(stroke
				(width 0.15)
				(type solid)
			)
			(layer "F.Fab")
		)
		(fp_rect
			(start 0.848 0.4)
			(end -0.85 -0.402)
			(stroke
				(width 0.15)
				(type solid)
			)
			(fill no)
			(layer "F.Fab")
		)
		(pad "1" smd roundrect
			(at -0.7 0 270)
			(size 0.8 1)
			(layers "F.Cu" "F.Mask" "F.Paste")
			(roundrect_rratio 0.2)
			(net 2 "GND")
			(pinfunction "C")
			(pintype "passive")
		)
		(pad "2" smd roundrect
			(at 0.7 0 270)
			(size 0.8 1)
			(layers "F.Cu" "F.Mask" "F.Paste")
			(roundrect_rratio 0.2)
			(net 64 "Net-(D3-A)")
			(pinfunction "A")
			(pintype "passive")
		)
	)
)
